# S9S_MB_2U (Grand Teton) — schematic netlist excerpt (pin names and nets, part order shuffled) for the footprints in the layout excerpt that follows; sources: Cadence DE-HDL packaged netlist, KiCad conversion of 03242023_DA0F0TMBIJ0_F0T_Motherboard_J_brd_V01_OCP.brd

C940  Q_CAP_DIFFBUS  DIFF BUS_0.22UF 6.3V 20% X6S  pkg C0201  page 173 : \1\ = P5E_CPU0_PE2_TX_C_DN<12> ; \2\ = P5E_CPU0_PE2_TX_DN<12>

J67  PICOPROBE_BXA  DELTA-L 4.0 EMPTY  pkg TRIANG_LAUNCH_3PXB  page 308
  \1_p\  = DELTA_L_85_5INCH_IN3_DP
  \2_n\  = DELTA_L_85_5INCH_IN3_DN
  \3_g\  = DELTA_L_GND_1

(kicad_pcb
	(version 20260206)
	(generator "pcbnew")
	(generator_version "10.0")
	(general
		(thickness 1.6)
		(legacy_teardrops no)
	)
	(paper "A4")
	(title_block
		(title "03242023_DA0F0TMBIJ0_F0T_Motherboard_J_brd_V01_OCP.brd")
		(comment 1 "Grand Teton / footprints 3798-3799 of 6105")
	)
	(layers
		(0 "F.Cu" signal "TOP")
		(4 "In1.Cu" signal "GND")
		(6 "In2.Cu" signal "IN1")
		(8 "In3.Cu" signal "GND1")
		(10 "In4.Cu" signal "IN2")
		(12 "In5.Cu" signal "GND2")
		(14 "In6.Cu" signal "IN3")
		(16 "In7.Cu" signal "GND3")
		(18 "In8.Cu" signal "VCC")
		(20 "In9.Cu" signal "VCC1")
		(22 "In10.Cu" signal "GND4")
		(24 "In11.Cu" signal "IN4")
		(26 "In12.Cu" signal "GND5")
		(28 "In13.Cu" signal "IN5")
		(30 "In14.Cu" signal "GND6")
		(32 "In15.Cu" signal "IN6")
		(34 "In16.Cu" signal "GND7")
		(2 "B.Cu" signal "BOTTOM")
		(9 "F.Adhes" user "F.Adhesive")
		(11 "B.Adhes" user "B.Adhesive")
		(13 "F.Paste" user "Package Geometry/Pastemask Top")
		(15 "B.Paste" user "Package Geometry/Pastemask Bottom")
		(5 "F.SilkS" user "Ref Des/Silkscreen Top")
		(7 "B.SilkS" user "Ref Des/Silkscreen Bottom")
		(1 "F.Mask" user "Board Geometry/Soldermask Top")
		(3 "B.Mask" user "Board Geometry/Soldermask Bottom")
		(17 "Dwgs.User" user "User.Drawings")
		(19 "Cmts.User" user "User.Comments")
		(21 "Eco1.User" user "User.Eco1")
		(23 "Eco2.User" user "User.Eco2")
		(25 "Edge.Cuts" user "Board Geometry/Outline")
		(27 "Margin" user)
		(31 "F.CrtYd" user "Package Geometry/Place Bound Top")
		(29 "B.CrtYd" user "Package Geometry/Place Bound Bottom")
		(35 "F.Fab" user "Ref Des/Assembly Top")
		(33 "B.Fab" user "Ref Des/Assembly Bottom")
	)
	(footprint ""
		(layer "F.Cu")
		(at 250.65482 -4.699 180)
		(property "Reference" "J67"
			(at -4.38785 -1.016 90)
			(unlocked yes)
			(layer "F.SilkS")
			(effects
				(font
					(size 0.7874 0.5842)
					(thickness 0.1524)
				)
				(justify left)
			)
		)
		(property "Value" ""
			(at 0 0 180)
			(layer "F.Fab")
			(effects
				(font
					(size 1.27 1.27)
				)
			)
		)
		(duplicate_pad_numbers_are_jumpers no)
		(fp_line
			(start 1.2192 2.1082)
			(end -1.2192 2.1082)
			(stroke
				(width 0.1524)
				(type default)
			)
			(layer "F.SilkS")
		)
		(fp_line
			(start 1.2192 -2.1082)
			(end 1.2192 2.1082)
			(stroke
				(width 0.1524)
				(type default)
			)
			(layer "F.SilkS")
		)
		(fp_line
			(start -1.2192 2.1082)
			(end -1.2192 -2.1082)
			(stroke
				(width 0.1524)
				(type default)
			)
			(layer "F.SilkS")
		)
		(fp_line
			(start -1.2192 -2.1082)
			(end 1.2192 -2.1082)
			(stroke
				(width 0.1524)
				(type default)
			)
			(layer "F.SilkS")
		)
		(pad "" np_thru_hole circle
			(at -2.8829 -1.27 90)
			(size 1.0414 1.0414)
			(drill 1.0414)
			(layers "*.Cu" "*.Mask")
			(clearance 0.381)
			(thermal_gap 0.381)
		)
		(pad "" np_thru_hole circle
			(at -2.8829 1.27 90)
			(size 1.0414 1.0414)
			(drill 1.0414)
			(layers "*.Cu" "*.Mask")
			(clearance 0.381)
			(thermal_gap 0.381)
		)
		(pad "" np_thru_hole circle
			(at 3.4671 -1.27 90)
			(size 1.0414 1.0414)
			(drill 1.0414)
			(layers "*.Cu" "*.Mask")
			(clearance 0.381)
			(thermal_gap 0.381)
		)
		(pad "" np_thru_hole circle
			(at 3.4671 1.27 90)
			(size 1.0414 1.0414)
			(drill 1.0414)
			(layers "*.Cu" "*.Mask")
			(clearance 0.381)
			(thermal_gap 0.381)
		)
		(pad "1" smd rect
			(at 0.8255 -0.249936 90)
			(size 0.3048 0.508)
			(layers "F.Cu" "F.Mask" "F.Paste")
			(net "DELTA_L_85_5INCH_IN3_DP")
		)
		(pad "2" smd rect
			(at 0.8255 0.249936 90)
			(size 0.3048 0.508)
			(layers "F.Cu" "F.Mask" "F.Paste")
			(net "DELTA_L_85_5INCH_IN3_DN")
		)
		(pad "3" smd circle
			(at 0 0 180)
			(size 0 0)
			(layers "F.Cu" "F.Mask" "F.Paste")
			(net "DELTA_L_GND_1")
		)
		(zone
			(layer "F.Cu")
			(hatch none 0.5)
			(connect_pads
				(clearance 0)
			)
			(min_thickness 0.25)
			(keepout
				(tracks not_allowed)
				(vias allowed)
				(pads allowed)
				(copperpour not_allowed)
				(footprints allowed)
			)
			(placement
				(enabled no)
				(sheetname "")
			)
			(fill
				(thermal_gap 0.5)
				(thermal_bridge_width 0.5)
				(island_removal_mode 0)
			)
			(polygon
				(pts
					(xy 249.53722 -4.15036) (xy 249.53722 -4.245864) (xy 250.13412 -4.245864) (xy 250.13412 -4.652264)
					(xy 249.53722 -4.652264) (xy 249.53722 -4.745736) (xy 250.13412 -4.745736) (xy 250.13412 -5.152136)
					(xy 249.53722 -5.152136) (xy 249.53722 -5.24764) (xy 250.23572 -5.24764) (xy 250.23572 -4.15036)
				)
			)
		)
		(zone
			(layers "F.Cu" "B.Cu" "In1.Cu" "In2.Cu" "In3.Cu" "In4.Cu" "In5.Cu" "In6.Cu"
				"In7.Cu" "In8.Cu" "In9.Cu" "In10.Cu" "In11.Cu" "In12.Cu" "In13.Cu" "In14.Cu"
				"In15.Cu" "In16.Cu"
			)
			(hatch none 0.5)
			(connect_pads
				(clearance 0)
			)
			(min_thickness 0.25)
			(keepout
				(tracks not_allowed)
				(vias allowed)
				(pads allowed)
				(copperpour not_allowed)
				(footprints allowed)
			)
			(placement
				(enabled no)
				(sheetname "")
			)
			(fill
				(thermal_gap 0.5)
				(thermal_bridge_width 0.5)
				(island_removal_mode 0)
			)
			(polygon
				(pts
					(arc
						(start 248.11482 -5.969)
						(mid 246.26062 -5.969)
						(end 248.11482 -5.969)
					)
				)
			)
		)
		(zone
			(layers "F.Cu" "B.Cu" "In1.Cu" "In2.Cu" "In3.Cu" "In4.Cu" "In5.Cu" "In6.Cu"
				"In7.Cu" "In8.Cu" "In9.Cu" "In10.Cu" "In11.Cu" "In12.Cu" "In13.Cu" "In14.Cu"
				"In15.Cu" "In16.Cu"
			)
			(hatch none 0.5)
			(connect_pads
				(clearance 0)
			)
			(min_thickness 0.25)
			(keepout
				(tracks not_allowed)
				(vias allowed)
				(pads allowed)
				(copperpour not_allowed)
				(footprints allowed)
			)
			(placement
				(enabled no)
				(sheetname "")
			)
			(fill
				(thermal_gap 0.5)
				(thermal_bridge_width 0.5)
				(island_removal_mode 0)
			)
			(polygon
				(pts
					(arc
						(start 248.11482 -3.429)
						(mid 246.26062 -3.429)
						(end 248.11482 -3.429)
					)
				)
			)
		)
		(zone
			(layers "F.Cu" "B.Cu" "In1.Cu" "In2.Cu" "In3.Cu" "In4.Cu" "In5.Cu" "In6.Cu"
				"In7.Cu" "In8.Cu" "In9.Cu" "In10.Cu" "In11.Cu" "In12.Cu" "In13.Cu" "In14.Cu"
				"In15.Cu" "In16.Cu"
			)
			(hatch none 0.5)
			(connect_pads
				(clearance 0)
			)
			(min_thickness 0.25)
			(keepout
				(tracks not_allowed)
				(vias allowed)
				(pads allowed)
				(copperpour not_allowed)
				(footprints allowed)
			)
			(placement
				(enabled no)
				(sheetname "")
			)
			(fill
				(thermal_gap 0.5)
				(thermal_bridge_width 0.5)
				(island_removal_mode 0)
			)
			(polygon
				(pts
					(arc
						(start 254.46482 -5.969)
						(mid 252.61062 -5.969)
						(end 254.46482 -5.969)
					)
				)
			)
		)
		(zone
			(layers "F.Cu" "B.Cu" "In1.Cu" "In2.Cu" "In3.Cu" "In4.Cu" "In5.Cu" "In6.Cu"
				"In7.Cu" "In8.Cu" "In9.Cu" "In10.Cu" "In11.Cu" "In12.Cu" "In13.Cu" "In14.Cu"
				"In15.Cu" "In16.Cu"
			)
			(hatch none 0.5)
			(connect_pads
				(clearance 0)
			)
			(min_thickness 0.25)
			(keepout
				(tracks not_allowed)
				(vias allowed)
				(pads allowed)
				(copperpour not_allowed)
				(footprints allowed)
			)
			(placement
				(enabled no)
				(sheetname "")
			)
			(fill
				(thermal_gap 0.5)
				(thermal_bridge_width 0.5)
				(island_removal_mode 0)
			)
			(polygon
				(pts
					(arc
						(start 254.46482 -3.429)
						(mid 252.61062 -3.429)
						(end 254.46482 -3.429)
					)
				)
			)
		)
	)
	(footprint ""
		(layer "F.Cu")
		(at 381.50165 -402.371052 -90)
		(property "Reference" "C940"
			(at 0 0 270)
			(layer "F.SilkS")
			(hide yes)
			(effects
				(font
					(size 1.27 1.27)
				)
			)
		)
		(property "Value" ""
			(at 0 0 270)
			(layer "F.Fab")
			(effects
				(font
					(size 1.27 1.27)
				)
			)
		)
		(duplicate_pad_numbers_are_jumpers no)
		(fp_line
			(start -0.299974 0.150114)
			(end -0.299974 -0.150114)
			(stroke
				(width 0.1)
				(type default)
			)
			(layer "F.Fab")
		)
		(fp_line
			(start 0.299974 0.150114)
			(end -0.299974 0.150114)
			(stroke
				(width 0.1)
				(type default)
			)
			(layer "F.Fab")
		)
		(fp_line
			(start -0.299974 -0.150114)
			(end 0.299974 -0.150114)
			(stroke
				(width 0.1)
				(type default)
			)
			(layer "F.Fab")
		)
		(fp_line
			(start 0.299974 -0.150114)
			(end 0.299974 0.150114)
			(stroke
				(width 0.1)
				(type default)
			)
			(layer "F.Fab")
		)
		(pad "1" smd rect
			(at -0.2667 0 270)
			(size 0.3048 0.381)
			(layers "F.Cu" "F.Mask" "F.Paste")
			(net "P5E_CPU0_PE2_TX_C_DN<12>")
		)
		(pad "2" smd rect
			(at 0.2667 0 270)
			(size 0.3048 0.381)
			(layers "F.Cu" "F.Mask" "F.Paste")
			(net "P5E_CPU0_PE2_TX_DN<12>")
		)
	)
)
